# S9S_MB_2U (Grand Teton) — schematic netlist excerpt (pin names and nets, part order shuffled) for the footprints in the layout excerpt that follows; sources: Cadence DE-HDL packaged netlist, KiCad conversion of 03242023_DA0F0TMBIJ0_F0T_Motherboard_J_brd_V01_OCP.brd

R146  Q_RES  4.75K 1% EMPTY  pkg 0402LF  page 197 : A = PVNN_TERM_CPU0 ; B = PECI_BMC_R
R1950  Q_RES  0 5% CHIP  pkg 0402LF  page 244 : A = FM_COMP_P3V3_AUX_VIN ; B = FM_COMP_P3V3_AUX_VIN_R

(kicad_pcb
	(version 20260206)
	(generator "pcbnew")
	(generator_version "10.0")
	(general
		(thickness 1.6)
		(legacy_teardrops no)
	)
	(paper "A4")
	(title_block
		(title "03242023_DA0F0TMBIJ0_F0T_Motherboard_J_brd_V01_OCP.brd")
		(comment 1 "Grand Teton / footprints 702-703 of 6105")
	)
	(layers
		(0 "F.Cu" signal "TOP")
		(4 "In1.Cu" signal "GND")
		(6 "In2.Cu" signal "IN1")
		(8 "In3.Cu" signal "GND1")
		(10 "In4.Cu" signal "IN2")
		(12 "In5.Cu" signal "GND2")
		(14 "In6.Cu" signal "IN3")
		(16 "In7.Cu" signal "GND3")
		(18 "In8.Cu" signal "VCC")
		(20 "In9.Cu" signal "VCC1")
		(22 "In10.Cu" signal "GND4")
		(24 "In11.Cu" signal "IN4")
		(26 "In12.Cu" signal "GND5")
		(28 "In13.Cu" signal "IN5")
		(30 "In14.Cu" signal "GND6")
		(32 "In15.Cu" signal "IN6")
		(34 "In16.Cu" signal "GND7")
		(2 "B.Cu" signal "BOTTOM")
		(9 "F.Adhes" user "F.Adhesive")
		(11 "B.Adhes" user "B.Adhesive")
		(13 "F.Paste" user "Package Geometry/Pastemask Top")
		(15 "B.Paste" user "Package Geometry/Pastemask Bottom")
		(5 "F.SilkS" user "Ref Des/Silkscreen Top")
		(7 "B.SilkS" user "Ref Des/Silkscreen Bottom")
		(1 "F.Mask" user "Board Geometry/Soldermask Top")
		(3 "B.Mask" user "Board Geometry/Soldermask Bottom")
		(17 "Dwgs.User" user "User.Drawings")
		(19 "Cmts.User" user "User.Comments")
		(21 "Eco1.User" user "User.Eco1")
		(23 "Eco2.User" user "User.Eco2")
		(25 "Edge.Cuts" user "Board Geometry/Outline")
		(27 "Margin" user)
		(31 "F.CrtYd" user "Package Geometry/Place Bound Top")
		(29 "B.CrtYd" user "Package Geometry/Place Bound Bottom")
		(35 "F.Fab" user "Ref Des/Assembly Top")
		(33 "B.Fab" user "Ref Des/Assembly Bottom")
	)
	(footprint ""
		(layer "F.Cu")
		(at 306.63388 -53.050948 90)
		(property "Reference" "R146"
			(at 0 0 90)
			(layer "F.SilkS")
			(hide yes)
			(effects
				(font
					(size 1.27 1.27)
				)
			)
		)
		(property "Value" ""
			(at 0 0 90)
			(layer "F.Fab")
			(effects
				(font
					(size 1.27 1.27)
				)
			)
		)
		(duplicate_pad_numbers_are_jumpers no)
		(fp_line
			(start 0.7874 -0.4064)
			(end 0.7874 0.4064)
			(stroke
				(width 0.1524)
				(type default)
			)
			(layer "F.SilkS")
		)
		(fp_line
			(start -0.7874 -0.4064)
			(end 0.7874 -0.4064)
			(stroke
				(width 0.1524)
				(type default)
			)
			(layer "F.SilkS")
		)
		(fp_line
			(start 0.7874 0.4064)
			(end -0.7874 0.4064)
			(stroke
				(width 0.1524)
				(type default)
			)
			(layer "F.SilkS")
		)
		(fp_line
			(start -0.7874 0.4064)
			(end -0.7874 -0.4064)
			(stroke
				(width 0.1524)
				(type default)
			)
			(layer "F.SilkS")
		)
		(fp_line
			(start -0.12065 -0.305054)
			(end -0.12065 -0.2794)
			(stroke
				(width 0.1)
				(type default)
			)
			(layer "F.Fab")
		)
		(fp_line
			(start -0.67945 -0.305054)
			(end -0.12065 -0.305054)
			(stroke
				(width 0.1)
				(type default)
			)
			(layer "F.Fab")
		)
		(fp_line
			(start 0.67945 -0.3048)
			(end 0.67945 0.3048)
			(stroke
				(width 0.1)
				(type default)
			)
			(layer "F.Fab")
		)
		(fp_line
			(start 0.12065 -0.3048)
			(end 0.67945 -0.3048)
			(stroke
				(width 0.1)
				(type default)
			)
			(layer "F.Fab")
		)
		(fp_line
			(start 0.12065 -0.2794)
			(end 0.12065 -0.3048)
			(stroke
				(width 0.1)
				(type default)
			)
			(layer "F.Fab")
		)
		(fp_line
			(start -0.12065 -0.2794)
			(end 0.12065 -0.2794)
			(stroke
				(width 0.1)
				(type default)
			)
			(layer "F.Fab")
		)
		(fp_line
			(start 0.120396 0.2794)
			(end -0.12065 0.2794)
			(stroke
				(width 0.1)
				(type default)
			)
			(layer "F.Fab")
		)
		(fp_line
			(start -0.12065 0.2794)
			(end -0.12065 0.3048)
			(stroke
				(width 0.1)
				(type default)
			)
			(layer "F.Fab")
		)
		(fp_line
			(start 0.67945 0.3048)
			(end 0.120396 0.3048)
			(stroke
				(width 0.1)
				(type default)
			)
			(layer "F.Fab")
		)
		(fp_line
			(start 0.120396 0.3048)
			(end 0.120396 0.2794)
			(stroke
				(width 0.1)
				(type default)
			)
			(layer "F.Fab")
		)
		(fp_line
			(start -0.12065 0.3048)
			(end -0.67945 0.3048)
			(stroke
				(width 0.1)
				(type default)
			)
			(layer "F.Fab")
		)
		(fp_line
			(start -0.67945 0.3048)
			(end -0.67945 -0.305054)
			(stroke
				(width 0.1)
				(type default)
			)
			(layer "F.Fab")
		)
		(pad "1" smd circle
			(at -0.40005 0 90)
			(size 0 0)
			(layers "F.Cu" "F.Mask" "F.Paste")
			(net "PVNN_TERM_CPU0")
		)
		(pad "2" smd circle
			(at 0.40005 0 90)
			(size 0 0)
			(layers "F.Cu" "F.Mask" "F.Paste")
			(net "PECI_BMC_R")
		)
	)
	(footprint ""
		(layer "F.Cu")
		(at 209.74558 -129.814828 180)
		(property "Reference" "R1950"
			(at 0 0 180)
			(layer "F.SilkS")
			(hide yes)
			(effects
				(font
					(size 1.27 1.27)
				)
			)
		)
		(property "Value" ""
			(at 0 0 180)
			(layer "F.Fab")
			(effects
				(font
					(size 1.27 1.27)
				)
			)
		)
		(duplicate_pad_numbers_are_jumpers no)
		(fp_line
			(start 0.7874 0.4064)
			(end -0.7874 0.4064)
			(stroke
				(width 0.1524)
				(type default)
			)
			(layer "F.SilkS")
		)
		(fp_line
			(start 0.7874 -0.4064)
			(end 0.7874 0.4064)
			(stroke
				(width 0.1524)
				(type default)
			)
			(layer "F.SilkS")
		)
		(fp_line
			(start -0.7874 0.4064)
			(end -0.7874 -0.4064)
			(stroke
				(width 0.1524)
				(type default)
			)
			(layer "F.SilkS")
		)
		(fp_line
			(start -0.7874 -0.4064)
			(end 0.7874 -0.4064)
			(stroke
				(width 0.1524)
				(type default)
			)
			(layer "F.SilkS")
		)
		(fp_line
			(start 0.67945 0.3048)
			(end 0.120396 0.3048)
			(stroke
				(width 0.1)
				(type default)
			)
			(layer "F.Fab")
		)
		(fp_line
			(start 0.67945 -0.3048)
			(end 0.67945 0.3048)
			(stroke
				(width 0.1)
				(type default)
			)
			(layer "F.Fab")
		)
		(fp_line
			(start 0.12065 -0.2794)
			(end 0.12065 -0.3048)
			(stroke
				(width 0.1)
				(type default)
			)
			(layer "F.Fab")
		)
		(fp_line
			(start 0.12065 -0.3048)
			(end 0.67945 -0.3048)
			(stroke
				(width 0.1)
				(type default)
			)
			(layer "F.Fab")
		)
		(fp_line
			(start 0.120396 0.3048)
			(end 0.120396 0.2794)
			(stroke
				(width 0.1)
				(type default)
			)
			(layer "F.Fab")
		)
		(fp_line
			(start 0.120396 0.2794)
			(end -0.12065 0.2794)
			(stroke
				(width 0.1)
				(type default)
			)
			(layer "F.Fab")
		)
		(fp_line
			(start -0.12065 0.3048)
			(end -0.67945 0.3048)
			(stroke
				(width 0.1)
				(type default)
			)
			(layer "F.Fab")
		)
		(fp_line
			(start -0.12065 0.2794)
			(end -0.12065 0.3048)
			(stroke
				(width 0.1)
				(type default)
			)
			(layer "F.Fab")
		)
		(fp_line
			(start -0.12065 -0.2794)
			(end 0.12065 -0.2794)
			(stroke
				(width 0.1)
				(type default)
			)
			(layer "F.Fab")
		)
		(fp_line
			(start -0.12065 -0.305054)
			(end -0.12065 -0.2794)
			(stroke
				(width 0.1)
				(type default)
			)
			(layer "F.Fab")
		)
		(fp_line
			(start -0.67945 0.3048)
			(end -0.67945 -0.305054)
			(stroke
				(width 0.1)
				(type default)
			)
			(layer "F.Fab")
		)
		(fp_line
			(start -0.67945 -0.305054)
			(end -0.12065 -0.305054)
			(stroke
				(width 0.1)
				(type default)
			)
			(layer "F.Fab")
		)
		(pad "1" smd circle
			(at -0.40005 0 180)
			(size 0 0)
			(layers "F.Cu" "F.Mask" "F.Paste")
			(net "FM_COMP_P3V3_AUX_VIN")
		)
		(pad "2" smd circle
			(at 0.40005 0 180)
			(size 0 0)
			(layers "F.Cu" "F.Mask" "F.Paste")
			(net "FM_COMP_P3V3_AUX_VIN_R")
		)
	)
)
